(kicad_sch (version 20230121) (generator eeschema)

  (paper "A3")

  (title_block
    (title "Thunderbolt PCIe Adaper")
    (date "2024-07-09")
    (rev "1.0.3")
    (comment 1 "www.antmicro.com")
    (comment 2 "Antmicro Ltd.")
  )


  (text "Thunderbolt - PCIe Adapter" (at 15.875 22.225 0)
    (effects (font (size 2.54 2.54) bold) (justify left bottom))
  )

  (symbol (lib_id "antmicroFiducialMarks:Fiducial_1mm_Mask3mm") (at 29.21 269.875 0) (unit 1)
    (in_bom no) (on_board yes) (dnp no) (fields_autoplaced)
    (property "Reference" "FID4" (at 34.29 268.605 0)
      (effects (font (size 1.27 1.27)) (justify left))
    )
    (property "Value" "Fiducial_1mm_Mask3mm" (at 34.29 271.145 0)
      (effects (font (size 1.27 1.27) (thickness 0.15)) (justify left))
    )
    (property "Footprint" "antmicro-footprints:Fiducial_1mm_Mask3mm" (at 36.83 274.955 0)
      (effects (font (size 1.27 1.27) (thickness 0.15)) (justify left bottom) hide)
    )
    (property "Datasheet" "" (at 36.525 279.095 0)
      (effects (font (size 1.27 1.27) (thickness 0.15)) (justify left bottom) hide)
    )
    (property "Author" "Antmicro" (at 36.525 277.825 0)
      (effects (font (size 1.27 1.27) (thickness 0.15)) (justify left bottom) hide)
    )
    (property "License" "Apache-2.0" (at 36.525 280.365 0)
      (effects (font (size 1.27 1.27) (thickness 0.15)) (justify left bottom) hide)
    )
    (instances
      (project "thunderbolt-pcie-adapter"
        (path ""
          (reference "FID4") (unit 1)
        )
      )
    )
  )

  (symbol (lib_id "antmicroFiducialMarks:Fiducial_1mm_Mask3mm") (at 29.21 255.905 0) (unit 1)
    (in_bom no) (on_board yes) (dnp no) (fields_autoplaced)
    (property "Reference" "FID2" (at 34.29 254.635 0)
      (effects (font (size 1.27 1.27)) (justify left))
    )
    (property "Value" "Fiducial_1mm_Mask3mm" (at 34.29 257.175 0)
      (effects (font (size 1.27 1.27) (thickness 0.15)) (justify left))
    )
    (property "Footprint" "antmicro-footprints:Fiducial_1mm_Mask3mm" (at 36.83 260.985 0)
      (effects (font (size 1.27 1.27) (thickness 0.15)) (justify left bottom) hide)
    )
    (property "Datasheet" "" (at 36.525 265.125 0)
      (effects (font (size 1.27 1.27) (thickness 0.15)) (justify left bottom) hide)
    )
    (property "Author" "Antmicro" (at 36.525 263.855 0)
      (effects (font (size 1.27 1.27) (thickness 0.15)) (justify left bottom) hide)
    )
    (property "License" "Apache-2.0" (at 36.525 266.395 0)
      (effects (font (size 1.27 1.27) (thickness 0.15)) (justify left bottom) hide)
    )
    (instances
      (project "thunderbolt-pcie-adapter"
        (path ""
          (reference "FID2") (unit 1)
        )
      )
    )
  )

  (symbol (lib_id "antmicroMechanicalParts:antmicro_logo") (at 113.665 270.51 0) (unit 1)
    (in_bom no) (on_board yes) (dnp no) (fields_autoplaced)
    (property "Reference" "N1" (at 119.38 268.5262 0)
      (effects (font (size 1.27 1.27) (thickness 0.15)) (justify left))
    )
    (property "Value" "antmicro_logo" (at 119.38 271.0662 0)
      (effects (font (size 1.27 1.27) (thickness 0.15)) (justify left))
    )
    (property "Footprint" "antmicro-footprints:antmicro-logo_scaled_12mm_mask" (at 128.905 280.67 0)
      (effects (font (size 1.27 1.27) (thickness 0.15)) (justify left bottom) hide)
    )
    (property "Datasheet" "" (at 128.905 283.21 0)
      (effects (font (size 1.27 1.27) (thickness 0.15)) (justify left bottom) hide)
    )
    (property "MPN" "" (at 113.665 270.51 0)
      (effects (font (size 1.27 1.27)))
    )
    (property "Manufacturer" "" (at 128.905 290.83 0)
      (effects (font (size 1.27 1.27) (thickness 0.15)) (justify left bottom) hide)
    )
    (property "Author" "Antmicro" (at 128.905 285.75 0)
      (effects (font (size 1.27 1.27) (thickness 0.15)) (justify left bottom) hide)
    )
    (property "License" "Apache-2.0" (at 128.905 288.29 0)
      (effects (font (size 1.27 1.27) (thickness 0.15)) (justify left bottom) hide)
    )
    (instances
      (project "thunderbolt-pcie-adapter"
        (path ""
          (reference "N1") (unit 1)
        )
      )
    )
  )

  (symbol (lib_id "antmicroFiducialMarks:Fiducial_1mm_Mask3mm") (at 71.12 262.89 0) (unit 1)
    (in_bom no) (on_board yes) (dnp no) (fields_autoplaced)
    (property "Reference" "FID7" (at 76.2 261.62 0)
      (effects (font (size 1.27 1.27)) (justify left))
    )
    (property "Value" "Fiducial_1mm_Mask3mm" (at 76.2 264.16 0)
      (effects (font (size 1.27 1.27) (thickness 0.15)) (justify left))
    )
    (property "Footprint" "antmicro-footprints:Fiducial_1mm_Mask3mm" (at 78.74 267.97 0)
      (effects (font (size 1.27 1.27) (thickness 0.15)) (justify left bottom) hide)
    )
    (property "Datasheet" "" (at 78.435 272.11 0)
      (effects (font (size 1.27 1.27) (thickness 0.15)) (justify left bottom) hide)
    )
    (property "Author" "Antmicro" (at 78.435 270.84 0)
      (effects (font (size 1.27 1.27) (thickness 0.15)) (justify left bottom) hide)
    )
    (property "License" "Apache-2.0" (at 78.435 273.38 0)
      (effects (font (size 1.27 1.27) (thickness 0.15)) (justify left bottom) hide)
    )
    (instances
      (project "thunderbolt-pcie-adapter"
        (path ""
          (reference "FID7") (unit 1)
        )
      )
    )
  )

  (symbol (lib_id "antmicroFiducialMarks:Fiducial_1mm_Mask3mm") (at 71.12 269.875 0) (unit 1)
    (in_bom no) (on_board yes) (dnp no) (fields_autoplaced)
    (property "Reference" "FID8" (at 76.2 268.605 0)
      (effects (font (size 1.27 1.27)) (justify left))
    )
    (property "Value" "Fiducial_1mm_Mask3mm" (at 76.2 271.145 0)
      (effects (font (size 1.27 1.27) (thickness 0.15)) (justify left))
    )
    (property "Footprint" "antmicro-footprints:Fiducial_1mm_Mask3mm" (at 78.74 274.955 0)
      (effects (font (size 1.27 1.27) (thickness 0.15)) (justify left bottom) hide)
    )
    (property "Datasheet" "" (at 78.435 279.095 0)
      (effects (font (size 1.27 1.27) (thickness 0.15)) (justify left bottom) hide)
    )
    (property "Author" "Antmicro" (at 78.435 277.825 0)
      (effects (font (size 1.27 1.27) (thickness 0.15)) (justify left bottom) hide)
    )
    (property "License" "Apache-2.0" (at 78.435 280.365 0)
      (effects (font (size 1.27 1.27) (thickness 0.15)) (justify left bottom) hide)
    )
    (instances
      (project "thunderbolt-pcie-adapter"
        (path ""
          (reference "FID8") (unit 1)
        )
      )
    )
  )

  (symbol (lib_id "antmicroFiducialMarks:Fiducial_1mm_Mask3mm") (at 29.21 262.89 0) (unit 1)
    (in_bom no) (on_board yes) (dnp no) (fields_autoplaced)
    (property "Reference" "FID3" (at 34.29 261.62 0)
      (effects (font (size 1.27 1.27)) (justify left))
    )
    (property "Value" "Fiducial_1mm_Mask3mm" (at 34.29 264.16 0)
      (effects (font (size 1.27 1.27) (thickness 0.15)) (justify left))
    )
    (property "Footprint" "antmicro-footprints:Fiducial_1mm_Mask3mm" (at 36.83 267.97 0)
      (effects (font (size 1.27 1.27) (thickness 0.15)) (justify left bottom) hide)
    )
    (property "Datasheet" "" (at 36.525 272.11 0)
      (effects (font (size 1.27 1.27) (thickness 0.15)) (justify left bottom) hide)
    )
    (property "Author" "Antmicro" (at 36.525 270.84 0)
      (effects (font (size 1.27 1.27) (thickness 0.15)) (justify left bottom) hide)
    )
    (property "License" "Apache-2.0" (at 36.525 273.38 0)
      (effects (font (size 1.27 1.27) (thickness 0.15)) (justify left bottom) hide)
    )
    (instances
      (project "thunderbolt-pcie-adapter"
        (path ""
          (reference "FID3") (unit 1)
        )
      )
    )
  )

  (symbol (lib_id "antmicroFiducialMarks:Fiducial_1mm_Mask3mm") (at 29.21 248.92 0) (unit 1)
    (in_bom no) (on_board yes) (dnp no) (fields_autoplaced)
    (property "Reference" "FID1" (at 34.29 247.65 0)
      (effects (font (size 1.27 1.27)) (justify left))
    )
    (property "Value" "Fiducial_1mm_Mask3mm" (at 34.29 250.19 0)
      (effects (font (size 1.27 1.27) (thickness 0.15)) (justify left))
    )
    (property "Footprint" "antmicro-footprints:Fiducial_1mm_Mask3mm" (at 36.83 254 0)
      (effects (font (size 1.27 1.27) (thickness 0.15)) (justify left bottom) hide)
    )
    (property "Datasheet" "" (at 36.525 258.14 0)
      (effects (font (size 1.27 1.27) (thickness 0.15)) (justify left bottom) hide)
    )
    (property "Author" "Antmicro" (at 36.525 256.87 0)
      (effects (font (size 1.27 1.27) (thickness 0.15)) (justify left bottom) hide)
    )
    (property "License" "Apache-2.0" (at 36.525 259.41 0)
      (effects (font (size 1.27 1.27) (thickness 0.15)) (justify left bottom) hide)
    )
    (instances
      (project "thunderbolt-pcie-adapter"
        (path ""
          (reference "FID1") (unit 1)
        )
      )
    )
  )

  (symbol (lib_id "antmicroFiducialMarks:Fiducial_1mm_Mask3mm") (at 71.12 255.905 0) (unit 1)
    (in_bom no) (on_board yes) (dnp no) (fields_autoplaced)
    (property "Reference" "FID6" (at 76.2 254.635 0)
      (effects (font (size 1.27 1.27)) (justify left))
    )
    (property "Value" "Fiducial_1mm_Mask3mm" (at 76.2 257.175 0)
      (effects (font (size 1.27 1.27) (thickness 0.15)) (justify left))
    )
    (property "Footprint" "antmicro-footprints:Fiducial_1mm_Mask3mm" (at 78.74 260.985 0)
      (effects (font (size 1.27 1.27) (thickness 0.15)) (justify left bottom) hide)
    )
    (property "Datasheet" "" (at 78.435 265.125 0)
      (effects (font (size 1.27 1.27) (thickness 0.15)) (justify left bottom) hide)
    )
    (property "Author" "Antmicro" (at 78.435 263.855 0)
      (effects (font (size 1.27 1.27) (thickness 0.15)) (justify left bottom) hide)
    )
    (property "License" "Apache-2.0" (at 78.435 266.395 0)
      (effects (font (size 1.27 1.27) (thickness 0.15)) (justify left bottom) hide)
    )
    (instances
      (project "thunderbolt-pcie-adapter"
        (path ""
          (reference "FID6") (unit 1)
        )
      )
    )
  )

  (symbol (lib_id "antmicroFiducialMarks:Fiducial_1mm_Mask3mm") (at 71.12 248.92 0) (unit 1)
    (in_bom no) (on_board yes) (dnp no) (fields_autoplaced)
    (property "Reference" "FID5" (at 76.2 247.65 0)
      (effects (font (size 1.27 1.27)) (justify left))
    )
    (property "Value" "Fiducial_1mm_Mask3mm" (at 76.2 250.19 0)
      (effects (font (size 1.27 1.27) (thickness 0.15)) (justify left))
    )
    (property "Footprint" "antmicro-footprints:Fiducial_1mm_Mask3mm" (at 78.74 254 0)
      (effects (font (size 1.27 1.27) (thickness 0.15)) (justify left bottom) hide)
    )
    (property "Datasheet" "" (at 78.435 258.14 0)
      (effects (font (size 1.27 1.27) (thickness 0.15)) (justify left bottom) hide)
    )
    (property "Author" "Antmicro" (at 78.435 256.87 0)
      (effects (font (size 1.27 1.27) (thickness 0.15)) (justify left bottom) hide)
    )
    (property "License" "Apache-2.0" (at 78.435 259.41 0)
      (effects (font (size 1.27 1.27) (thickness 0.15)) (justify left bottom) hide)
    )
    (instances
      (project "thunderbolt-pcie-adapter"
        (path ""
          (reference "FID5") (unit 1)
        )
      )
    )
  )

  (sheet (at 113.03 54.61) (size 77.47 64.77) (fields_autoplaced)
    (stroke (width 0.1524) (type solid))
    (fill (color 0 0 0 0.0000))
    (property "Sheetname" "Connectors" (at 113.03 53.8984 0)
      (effects (font (size 1.27 1.27)) (justify left bottom))
    )
    (property "Sheetfile" "connectors.kicad_sch" (at 113.03 119.9646 0)
      (effects (font (size 1.27 1.27)) (justify left top))
    )
    (instances
      (project "thunderbolt-pcie-adapter"
        (path "" (page "2"))
      )
    )
  )

  (sheet (at 233.68 137.16) (size 77.47 64.77) (fields_autoplaced)
    (stroke (width 0.1524) (type solid))
    (fill (color 0 0 0 0.0000))
    (property "Sheetname" "TB Controller" (at 233.68 136.4484 0)
      (effects (font (size 1.27 1.27)) (justify left bottom))
    )
    (property "Sheetfile" "tb.kicad_sch" (at 233.68 202.5146 0)
      (effects (font (size 1.27 1.27)) (justify left top))
    )
    (instances
      (project "thunderbolt-pcie-adapter"
        (path "" (page "5"))
      )
    )
  )

  (sheet (at 233.68 54.61) (size 77.47 64.77) (fields_autoplaced)
    (stroke (width 0.1524) (type solid))
    (fill (color 0 0 0 0.0000))
    (property "Sheetname" "Power" (at 233.68 53.8984 0)
      (effects (font (size 1.27 1.27)) (justify left bottom))
    )
    (property "Sheetfile" "power.kicad_sch" (at 233.68 119.9646 0)
      (effects (font (size 1.27 1.27)) (justify left top))
    )
    (instances
      (project "thunderbolt-pcie-adapter"
        (path "" (page "3"))
      )
    )
  )

  (sheet (at 113.03 137.16) (size 77.47 64.77) (fields_autoplaced)
    (stroke (width 0.1524) (type solid))
    (fill (color 0 0 0 0.0000))
    (property "Sheetname" "Thunderbolt Controller - Power" (at 113.03 136.4484 0)
      (effects (font (size 1.27 1.27)) (justify left bottom))
    )
    (property "Sheetfile" "tb-power.kicad_sch" (at 113.03 202.5146 0)
      (effects (font (size 1.27 1.27)) (justify left top))
    )
    (instances
      (project "thunderbolt-pcie-adapter"
        (path "" (page "4"))
      )
    )
  )

  (sheet_instances
    (path "/" (page "1"))
  )
)
